(kicad_pcb
	(version 20241229)
	(generator "pcbnew")
	(generator_version "9.0")
	(general
		(thickness 1.62)
		(legacy_teardrops no)
	)
	(paper "A3")
	(title_block
		(title "COM Express 7 Baseboard")
		(date "2025-02-04")
		(rev "1.1.2")
		(company "Antmicro Ltd")
		(comment 1 "www.antmicro.com")
		(comment 9 "footprints 702-707 of 802")
	)
	(layers
		(0 "F.Cu" signal)
		(4 "In1.Cu" signal)
		(6 "In2.Cu" signal)
		(8 "In3.Cu" signal)
		(10 "In4.Cu" signal)
		(12 "In5.Cu" signal)
		(14 "In6.Cu" signal)
		(2 "B.Cu" signal)
		(9 "F.Adhes" user "F.Adhesive")
		(11 "B.Adhes" user "B.Adhesive")
		(13 "F.Paste" user)
		(15 "B.Paste" user)
		(5 "F.SilkS" user "F.Silkscreen")
		(7 "B.SilkS" user "B.Silkscreen")
		(1 "F.Mask" user)
		(3 "B.Mask" user)
		(17 "Dwgs.User" user "User.Drawings")
		(19 "Cmts.User" user "User.Comments")
		(21 "Eco1.User" user "User.Eco1")
		(23 "Eco2.User" user "User.Eco2")
		(25 "Edge.Cuts" user)
		(27 "Margin" user)
		(31 "F.CrtYd" user "F.Courtyard")
		(29 "B.CrtYd" user "B.Courtyard")
		(35 "F.Fab" user)
		(33 "B.Fab" user)
	)
	(footprint "antmicro-footprints:R_0402_1005Metric"
		(layer "B.Cu")
		(at 130.7 133.87 180)
		(descr "Resistor SMD 0402")
		(tags "resistor SMD 0402")
		(property "Reference" "R301"
			(at 0.45 4.91 0)
			(layer "B.SilkS")
			(effects
				(font
					(size 0.7 0.7)
					(thickness 0.15)
				)
				(justify left bottom mirror)
			)
		)
		(property "Value" "R_10k_0402"
			(at -1.011843 -1.772047 0)
			(layer "B.Fab")
			(effects
				(font
					(size 0.7 0.7)
					(thickness 0.15)
				)
				(justify left bottom mirror)
			)
		)
		(property "Datasheet" "https://www.bourns.com/docs/product-datasheets/cr.pdf"
			(at 0 0 180)
			(layer "F.Fab")
			(hide yes)
			(effects
				(font
					(size 1.27 1.27)
					(thickness 0.15)
				)
			)
		)
		(property "Author" "Antmicro"
			(at 261.4 267.74 0)
			(layer "B.Fab")
			(hide yes)
			(effects
				(font
					(size 1 1)
					(thickness 0.15)
				)
				(justify mirror)
			)
		)
		(property "License" "Apache-2.0"
			(at 261.4 267.74 0)
			(layer "B.Fab")
			(hide yes)
			(effects
				(font
					(size 1 1)
					(thickness 0.15)
				)
				(justify mirror)
			)
		)
		(property "MPN" "CR0402-FX-1002GLF"
			(at 261.4 267.74 0)
			(layer "B.Fab")
			(hide yes)
			(effects
				(font
					(size 1 1)
					(thickness 0.15)
				)
				(justify mirror)
			)
		)
		(property "Manufacturer" "Bourns"
			(at 261.4 267.74 0)
			(layer "B.Fab")
			(hide yes)
			(effects
				(font
					(size 1 1)
					(thickness 0.15)
				)
				(justify mirror)
			)
		)
		(property "Public" "False"
			(at 261.4 267.74 0)
			(layer "B.Fab")
			(hide yes)
			(effects
				(font
					(size 1 1)
					(thickness 0.15)
				)
				(justify mirror)
			)
		)
		(property "Tolerance" "1%"
			(at 261.4 267.74 0)
			(layer "B.Fab")
			(hide yes)
			(effects
				(font
					(size 1 1)
					(thickness 0.15)
				)
				(justify mirror)
			)
		)
		(property "Val" "10k"
			(at 261.4 267.74 0)
			(layer "B.Fab")
			(hide yes)
			(effects
				(font
					(size 1 1)
					(thickness 0.15)
				)
				(justify mirror)
			)
		)
		(sheetname "KR to SFI #2")
		(sheetfile "kr_sfi.kicad_sch")
		(attr smd)
		(fp_rect
			(start -0.925 0.47)
			(end 0.925 -0.47)
			(stroke
				(width 0.05)
				(type default)
			)
			(fill no)
			(layer "B.CrtYd")
		)
		(fp_rect
			(start -0.5 0.25)
			(end 0.5 -0.25)
			(stroke
				(width 0.15)
				(type solid)
			)
			(fill no)
			(layer "B.Fab")
		)
		(pad "1" smd roundrect
			(at -0.48 0 180)
			(size 0.59 0.64)
			(layers "B.Cu" "B.Mask" "B.Paste")
			(roundrect_rratio 0.25)
			(net 681 "Net-(U45B-~{PDTRXB})")
			(pintype "passive")
			(teardrops
				(best_length_ratio 0.2)
				(max_length 1)
				(best_width_ratio 0.9)
				(max_width 2)
				(curved_edges yes)
				(filter_ratio 0.9)
				(enabled yes)
				(allow_two_segments yes)
				(prefer_zone_connections yes)
			)
		)
		(pad "2" smd roundrect
			(at 0.48 0 180)
			(size 0.59 0.64)
			(layers "B.Cu" "B.Mask" "B.Paste")
			(roundrect_rratio 0.25)
			(net 78 "+1V8")
			(pintype "passive")
			(teardrops
				(best_length_ratio 0.2)
				(max_length 1)
				(best_width_ratio 0.9)
				(max_width 2)
				(curved_edges yes)
				(filter_ratio 0.9)
				(enabled yes)
				(allow_two_segments yes)
				(prefer_zone_connections yes)
			)
		)
	)
	(footprint "antmicro-footprints:C_0402_1005Metric"
		(layer "B.Cu")
		(at 150.45 132.36 -90)
		(descr "Capacitor SMD 0402")
		(tags "capacitor SMD 0402")
		(property "Reference" "C171"
			(at -3.65 -0.45 90)
			(layer "B.SilkS")
			(effects
				(font
					(size 0.7 0.7)
					(thickness 0.15)
				)
				(justify left bottom mirror)
			)
		)
		(property "Value" "C_100n_0402"
			(at -1.022927 -2.155213 90)
			(layer "B.Fab")
			(effects
				(font
					(size 0.7 0.7)
					(thickness 0.15)
				)
				(justify left bottom mirror)
			)
		)
		(property "Datasheet" "https://www.murata.com/products/productdetail?partno=GRM155R61H104KE14%23"
			(at 0 0 270)
			(layer "F.Fab")
			(hide yes)
			(effects
				(font
					(size 1.27 1.27)
					(thickness 0.15)
				)
			)
		)
		(property "Author" "Antmicro"
			(at 18.09 282.81 0)
			(layer "B.Fab")
			(hide yes)
			(effects
				(font
					(size 1 1)
					(thickness 0.15)
				)
				(justify mirror)
			)
		)
		(property "Dielectric" "X5R"
			(at 18.09 282.81 0)
			(layer "B.Fab")
			(hide yes)
			(effects
				(font
					(size 1 1)
					(thickness 0.15)
				)
				(justify mirror)
			)
		)
		(property "License" "Apache-2.0"
			(at 18.09 282.81 0)
			(layer "B.Fab")
			(hide yes)
			(effects
				(font
					(size 1 1)
					(thickness 0.15)
				)
				(justify mirror)
			)
		)
		(property "MPN" "GRM155R61H104KE14D"
			(at 18.09 282.81 0)
			(layer "B.Fab")
			(hide yes)
			(effects
				(font
					(size 1 1)
					(thickness 0.15)
				)
				(justify mirror)
			)
		)
		(property "Manufacturer" "Murata"
			(at 18.09 282.81 0)
			(layer "B.Fab")
			(hide yes)
			(effects
				(font
					(size 1 1)
					(thickness 0.15)
				)
				(justify mirror)
			)
		)
		(property "Public" "False"
			(at 18.09 282.81 0)
			(layer "B.Fab")
			(hide yes)
			(effects
				(font
					(size 1 1)
					(thickness 0.15)
				)
				(justify mirror)
			)
		)
		(property "Val" "100n"
			(at 18.09 282.81 0)
			(layer "B.Fab")
			(hide yes)
			(effects
				(font
					(size 1 1)
					(thickness 0.15)
				)
				(justify mirror)
			)
		)
		(property "Voltage" "50V"
			(at 18.09 282.81 0)
			(layer "B.Fab")
			(hide yes)
			(effects
				(font
					(size 1 1)
					(thickness 0.15)
				)
				(justify mirror)
			)
		)
		(sheetname "KR to SFI #1")
		(sheetfile "kr_sfi.kicad_sch")
		(attr smd)
		(fp_rect
			(start -0.925 0.47)
			(end 0.925 -0.47)
			(stroke
				(width 0.05)
				(type default)
			)
			(fill no)
			(layer "B.CrtYd")
		)
		(fp_line
			(start -0.494 0.25)
			(end -0.494 -0.248)
			(stroke
				(width 0.15)
				(type solid)
			)
			(layer "B.Fab")
		)
		(fp_line
			(start 0.504 0.25)
			(end -0.494 0.25)
			(stroke
				(width 0.15)
				(type solid)
			)
			(layer "B.Fab")
		)
		(fp_line
			(start -0.494 -0.248)
			(end 0.504 -0.248)
			(stroke
				(width 0.15)
				(type solid)
			)
			(layer "B.Fab")
		)
		(fp_line
			(start 0.504 -0.248)
			(end 0.504 0.25)
			(stroke
				(width 0.15)
				(type solid)
			)
			(layer "B.Fab")
		)
		(pad "1" smd roundrect
			(at -0.48 0 270)
			(size 0.59 0.64)
			(layers "B.Cu" "B.Mask" "B.Paste")
			(roundrect_rratio 0.25)
			(net 1 "GND")
			(pintype "passive")
			(teardrops
				(best_length_ratio 0.2)
				(max_length 1)
				(best_width_ratio 0.9)
				(max_width 2)
				(curved_edges yes)
				(filter_ratio 0.9)
				(enabled yes)
				(allow_two_segments yes)
				(prefer_zone_connections yes)
			)
		)
		(pad "2" smd roundrect
			(at 0.48 0 270)
			(size 0.59 0.64)
			(layers "B.Cu" "B.Mask" "B.Paste")
			(roundrect_rratio 0.25)
			(net 74 "+1V0")
			(pintype "passive")
			(teardrops
				(best_length_ratio 0.2)
				(max_length 1)
				(best_width_ratio 0.9)
				(max_width 2)
				(curved_edges yes)
				(filter_ratio 0.9)
				(enabled yes)
				(allow_two_segments yes)
				(prefer_zone_connections yes)
			)
		)
	)
	(footprint "antmicro-footprints:C_0402_1005Metric"
		(layer "B.Cu")
		(at 107.893 165.355571 180)
		(descr "Capacitor SMD 0402")
		(tags "capacitor SMD 0402")
		(property "Reference" "C141"
			(at -3.657 0.045571 0)
			(layer "B.SilkS")
			(effects
				(font
					(size 0.7 0.7)
					(thickness 0.15)
				)
				(justify left bottom mirror)
			)
		)
		(property "Value" "C_220n_0402"
			(at -1.022927 -2.155213 0)
			(layer "B.Fab")
			(effects
				(font
					(size 0.7 0.7)
					(thickness 0.15)
				)
				(justify left bottom mirror)
			)
		)
		(property "Datasheet" "https://www.yageo.com/en/Chart/Download/pdf/CC0402KRX5R6BB224"
			(at 0 0 180)
			(layer "F.Fab")
			(hide yes)
			(effects
				(font
					(size 1.27 1.27)
					(thickness 0.15)
				)
			)
		)
		(property "Author" "Antmicro"
			(at 215.786 330.711142 0)
			(layer "B.Fab")
			(hide yes)
			(effects
				(font
					(size 1 1)
					(thickness 0.15)
				)
				(justify mirror)
			)
		)
		(property "Dielectric" ""
			(at 215.786 330.711142 0)
			(layer "B.Fab")
			(hide yes)
			(effects
				(font
					(size 1 1)
					(thickness 0.15)
				)
				(justify mirror)
			)
		)
		(property "License" "Apache-2.0"
			(at 215.786 330.711142 0)
			(layer "B.Fab")
			(hide yes)
			(effects
				(font
					(size 1 1)
					(thickness 0.15)
				)
				(justify mirror)
			)
		)
		(property "MPN" "CC0402KRX5R6BB224"
			(at 215.786 330.711142 0)
			(layer "B.Fab")
			(hide yes)
			(effects
				(font
					(size 1 1)
					(thickness 0.15)
				)
				(justify mirror)
			)
		)
		(property "Manufacturer" "YAGEO"
			(at 215.786 330.711142 0)
			(layer "B.Fab")
			(hide yes)
			(effects
				(font
					(size 1 1)
					(thickness 0.15)
				)
				(justify mirror)
			)
		)
		(property "Public" "False"
			(at 215.786 330.711142 0)
			(layer "B.Fab")
			(hide yes)
			(effects
				(font
					(size 1 1)
					(thickness 0.15)
				)
				(justify mirror)
			)
		)
		(property "Val" "220n"
			(at 215.786 330.711142 0)
			(layer "B.Fab")
			(hide yes)
			(effects
				(font
					(size 1 1)
					(thickness 0.15)
				)
				(justify mirror)
			)
		)
		(property "Voltage" ""
			(at 215.786 330.711142 0)
			(layer "B.Fab")
			(hide yes)
			(effects
				(font
					(size 1 1)
					(thickness 0.15)
				)
				(justify mirror)
			)
		)
		(sheetname "PCIe redriver")
		(sheetfile "pcie_redriver.kicad_sch")
		(attr smd)
		(fp_rect
			(start -0.925 0.47)
			(end 0.925 -0.47)
			(stroke
				(width 0.05)
				(type default)
			)
			(fill no)
			(layer "B.CrtYd")
		)
		(fp_line
			(start 0.504 0.25)
			(end -0.494 0.25)
			(stroke
				(width 0.15)
				(type solid)
			)
			(layer "B.Fab")
		)
		(fp_line
			(start 0.504 -0.248)
			(end 0.504 0.25)
			(stroke
				(width 0.15)
				(type solid)
			)
			(layer "B.Fab")
		)
		(fp_line
			(start -0.494 0.25)
			(end -0.494 -0.248)
			(stroke
				(width 0.15)
				(type solid)
			)
			(layer "B.Fab")
		)
		(fp_line
			(start -0.494 -0.248)
			(end 0.504 -0.248)
			(stroke
				(width 0.15)
				(type solid)
			)
			(layer "B.Fab")
		)
		(pad "1" smd roundrect
			(at -0.48 0 180)
			(size 0.59 0.64)
			(layers "B.Cu" "B.Mask" "B.Paste")
			(roundrect_rratio 0.25)
			(net 962 "/PCIe redriver/PCIe_{O}_C.TX1+")
			(pintype "passive")
			(teardrops
				(best_length_ratio 0.2)
				(max_length 1)
				(best_width_ratio 0.9)
				(max_width 2)
				(curved_edges yes)
				(filter_ratio 0.9)
				(enabled yes)
				(allow_two_segments yes)
				(prefer_zone_connections yes)
			)
		)
		(pad "2" smd roundrect
			(at 0.48 0 180)
			(size 0.59 0.64)
			(layers "B.Cu" "B.Mask" "B.Paste")
			(roundrect_rratio 0.25)
			(net 102 "/OCuLink/PCIe_{x4}.TX1+")
			(pintype "passive")
			(teardrops
				(best_length_ratio 0.2)
				(max_length 1)
				(best_width_ratio 0.9)
				(max_width 2)
				(curved_edges yes)
				(filter_ratio 0.9)
				(enabled yes)
				(allow_two_segments yes)
				(prefer_zone_connections yes)
			)
		)
	)
	(footprint "antmicro-footprints:R_0402_1005Metric"
		(layer "B.Cu")
		(at 157.9 142.36 180)
		(descr "Resistor SMD 0402")
		(tags "resistor SMD 0402")
		(property "Reference" "R261"
			(at -3.7 -0.4 0)
			(layer "B.SilkS")
			(effects
				(font
					(size 0.7 0.7)
					(thickness 0.15)
				)
				(justify left bottom mirror)
			)
		)
		(property "Value" "R_10k_0402"
			(at -1.011843 -1.772047 0)
			(layer "B.Fab")
			(effects
				(font
					(size 0.7 0.7)
					(thickness 0.15)
				)
				(justify left bottom mirror)
			)
		)
		(property "Datasheet" "https://www.bourns.com/docs/product-datasheets/cr.pdf"
			(at 0 0 180)
			(layer "F.Fab")
			(hide yes)
			(effects
				(font
					(size 1.27 1.27)
					(thickness 0.15)
				)
			)
		)
		(property "Author" "Antmicro"
			(at 315.8 284.72 0)
			(layer "B.Fab")
			(hide yes)
			(effects
				(font
					(size 1 1)
					(thickness 0.15)
				)
				(justify mirror)
			)
		)
		(property "License" "Apache-2.0"
			(at 315.8 284.72 0)
			(layer "B.Fab")
			(hide yes)
			(effects
				(font
					(size 1 1)
					(thickness 0.15)
				)
				(justify mirror)
			)
		)
		(property "MPN" "CR0402-FX-1002GLF"
			(at 315.8 284.72 0)
			(layer "B.Fab")
			(hide yes)
			(effects
				(font
					(size 1 1)
					(thickness 0.15)
				)
				(justify mirror)
			)
		)
		(property "Manufacturer" "Bourns"
			(at 315.8 284.72 0)
			(layer "B.Fab")
			(hide yes)
			(effects
				(font
					(size 1 1)
					(thickness 0.15)
				)
				(justify mirror)
			)
		)
		(property "Public" "False"
			(at 315.8 284.72 0)
			(layer "B.Fab")
			(hide yes)
			(effects
				(font
					(size 1 1)
					(thickness 0.15)
				)
				(justify mirror)
			)
		)
		(property "Tolerance" "1%"
			(at 315.8 284.72 0)
			(layer "B.Fab")
			(hide yes)
			(effects
				(font
					(size 1 1)
					(thickness 0.15)
				)
				(justify mirror)
			)
		)
		(property "Val" "10k"
			(at 315.8 284.72 0)
			(layer "B.Fab")
			(hide yes)
			(effects
				(font
					(size 1 1)
					(thickness 0.15)
				)
				(justify mirror)
			)
		)
		(sheetname "KR to SFI #1")
		(sheetfile "kr_sfi.kicad_sch")
		(attr smd)
		(fp_rect
			(start -0.925 0.47)
			(end 0.925 -0.47)
			(stroke
				(width 0.05)
				(type default)
			)
			(fill no)
			(layer "B.CrtYd")
		)
		(fp_rect
			(start -0.5 0.25)
			(end 0.5 -0.25)
			(stroke
				(width 0.15)
				(type solid)
			)
			(fill no)
			(layer "B.Fab")
		)
		(pad "1" smd roundrect
			(at -0.48 0 180)
			(size 0.59 0.64)
			(layers "B.Cu" "B.Mask" "B.Paste")
			(roundrect_rratio 0.25)
			(net 1 "GND")
			(pintype "passive")
			(teardrops
				(best_length_ratio 0.2)
				(max_length 1)
				(best_width_ratio 0.9)
				(max_width 2)
				(curved_edges yes)
				(filter_ratio 0.9)
				(enabled yes)
				(allow_two_segments yes)
				(prefer_zone_connections yes)
			)
		)
		(pad "2" smd roundrect
			(at 0.48 0 180)
			(size 0.59 0.64)
			(layers "B.Cu" "B.Mask" "B.Paste")
			(roundrect_rratio 0.25)
			(net 655 "Net-(U43C-PRTAD0)")
			(pintype "passive")
			(teardrops
				(best_length_ratio 0.2)
				(max_length 1)
				(best_width_ratio 0.9)
				(max_width 2)
				(curved_edges yes)
				(filter_ratio 0.9)
				(enabled yes)
				(allow_two_segments yes)
				(prefer_zone_connections yes)
			)
		)
	)
	(footprint "antmicro-footprints:C_0603_1608Metric"
		(layer "B.Cu")
		(at 137 161.56)
		(descr "Capacitor SMD 0603")
		(tags "capacitor 0603")
		(property "Reference" "C23"
			(at -3.35 0.45 0)
			(layer "B.SilkS")
			(effects
				(font
					(size 0.7 0.7)
					(thickness 0.15)
				)
				(justify right bottom mirror)
			)
		)
		(property "Value" "C_22u_16V_0603"
			(at -1.42757 -1.770288 0)
			(layer "B.Fab")
			(effects
				(font
					(size 0.7 0.7)
					(thickness 0.15)
				)
				(justify right bottom mirror)
			)
		)
		(property "Datasheet" "https://product.samsungsem.com/mlcc/CL10A226MO7JZN.do"
			(at 0 0 0)
			(layer "F.Fab")
			(hide yes)
			(effects
				(font
					(size 1.27 1.27)
					(thickness 0.15)
				)
			)
		)
		(property "Author" "Antmicro"
			(at 0 0 0)
			(layer "B.Fab")
			(hide yes)
			(effects
				(font
					(size 1 1)
					(thickness 0.15)
				)
				(justify mirror)
			)
		)
		(property "Dielectric" ""
			(at 0 0 0)
			(layer "B.Fab")
			(hide yes)
			(effects
				(font
					(size 1 1)
					(thickness 0.15)
				)
				(justify mirror)
			)
		)
		(property "License" "Apache-2.0"
			(at 0 0 0)
			(layer "B.Fab")
			(hide yes)
			(effects
				(font
					(size 1 1)
					(thickness 0.15)
				)
				(justify mirror)
			)
		)
		(property "MPN" "CL10A226MO7JZNC"
			(at 0 0 0)
			(layer "B.Fab")
			(hide yes)
			(effects
				(font
					(size 1 1)
					(thickness 0.15)
				)
				(justify mirror)
			)
		)
		(property "Manufacturer" "Samsung Electro-Mechanics"
			(at 0 0 0)
			(layer "B.Fab")
			(hide yes)
			(effects
				(font
					(size 1 1)
					(thickness 0.15)
				)
				(justify mirror)
			)
		)
		(property "Public" "False"
			(at 0 0 0)
			(layer "B.Fab")
			(hide yes)
			(effects
				(font
					(size 1 1)
					(thickness 0.15)
				)
				(justify mirror)
			)
		)
		(property "Val" "22u"
			(at 0 0 0)
			(layer "B.Fab")
			(hide yes)
			(effects
				(font
					(size 1 1)
					(thickness 0.15)
				)
				(justify mirror)
			)
		)
		(property "Voltage" "16V"
			(at 0 0 0)
			(layer "B.Fab")
			(hide yes)
			(effects
				(font
					(size 1 1)
					(thickness 0.15)
				)
				(justify mirror)
			)
		)
		(sheetname "2xSFP+")
		(sheetfile "2xSFP+.kicad_sch")
		(attr smd)
		(fp_line
			(start 0.15 -0.4)
			(end -0.15 -0.4)
			(stroke
				(width 0.15)
				(type solid)
			)
			(layer "B.SilkS")
		)
		(fp_line
			(start 0.15 0.4)
			(end -0.15 0.4)
			(stroke
				(width 0.15)
				(type solid)
			)
			(layer "B.SilkS")
		)
		(fp_rect
			(start -1.25 0.65)
			(end 1.25 -0.65)
			(stroke
				(width 0.05)
				(type solid)
			)
			(fill no)
			(layer "B.CrtYd")
		)
		(fp_rect
			(start -0.8 0.4)
			(end 0.8 -0.4)
			(stroke
				(width 0.15)
				(type solid)
			)
			(fill no)
			(layer "B.Fab")
		)
		(pad "1" smd roundrect
			(at -0.7 0)
			(size 0.8 1)
			(layers "B.Cu" "B.Mask" "B.Paste")
			(roundrect_rratio 0.2)
			(net 1 "GND")
			(pintype "passive")
			(teardrops
				(best_length_ratio 0.2)
				(max_length 1)
				(best_width_ratio 0.9)
				(max_width 2)
				(curved_edges yes)
				(filter_ratio 0.9)
				(enabled yes)
				(allow_two_segments yes)
				(prefer_zone_connections yes)
			)
		)
		(pad "2" smd roundrect
			(at 0.7 0)
			(size 0.8 1)
			(layers "B.Cu" "B.Mask" "B.Paste")
			(roundrect_rratio 0.2)
			(net 2 "+3V3")
			(pintype "passive")
			(teardrops
				(best_length_ratio 0.2)
				(max_length 1)
				(best_width_ratio 0.9)
				(max_width 2)
				(curved_edges yes)
				(filter_ratio 0.9)
				(enabled yes)
				(allow_two_segments yes)
				(prefer_zone_connections yes)
			)
		)
	)
	(footprint "antmicro-footprints:TP_SMD_0.75mm"
		(layer "B.Cu")
		(at 223.2 165.25)
		(property "Reference" "TP39"
			(at -0.45 -0.45 90)
			(layer "B.SilkS")
			(effects
				(font
					(size 0.7 0.7)
					(thickness 0.15)
				)
				(justify right top mirror)
			)
		)
		(property "Value" "TP_0.75mm_SMD"
			(at 0 -1.2 0)
			(layer "B.Fab")
			(effects
				(font
					(size 0.7 0.7)
					(thickness 0.15)
				)
				(justify right top mirror)
			)
		)
		(property "Author" "Antmicro"
			(at 364.2 295.32 0)
			(layer "B.Fab")
			(hide yes)
			(effects
				(font
					(size 1 1)
					(thickness 0.15)
				)
				(justify mirror)
			)
		)
		(property "License" "Apache-2.0"
			(at 364.2 295.32 0)
			(layer "B.Fab")
			(hide yes)
			(effects
				(font
					(size 1 1)
					(thickness 0.15)
				)
				(justify mirror)
			)
		)
		(property "MPN" ""
			(at 364.2 295.32 0)
			(layer "B.Fab")
			(hide yes)
			(effects
				(font
					(size 1 1)
					(thickness 0.15)
				)
				(justify mirror)
			)
		)
		(property "Manufacturer" ""
			(at 364.2 295.32 0)
			(layer "B.Fab")
			(hide yes)
			(effects
				(font
					(size 1 1)
					(thickness 0.15)
				)
				(justify mirror)
			)
		)
		(property "Public" "False"
			(at 364.2 295.32 0)
			(layer "B.Fab")
			(hide yes)
			(effects
				(font
					(size 1 1)
					(thickness 0.15)
				)
				(justify mirror)
			)
		)
		(sheetname "Com Express 7 MGMT")
		(sheetfile "com_express_7_mgmt.kicad_sch")
		(attr exclude_from_pos_files exclude_from_bom)
		(fp_circle
			(center 0 0)
			(end 0.475 0)
			(stroke
				(width 0.05)
				(type default)
			)
			(fill no)
			(layer "B.CrtYd")
		)
		(pad "1" smd circle
			(at 0 0)
			(size 0.75 0.75)
			(layers "B.Cu" "B.Mask")
			(net 342 "Net-(J12D-TPM_PP)")
			(pinfunction "1")
			(pintype "passive")
			(teardrops
				(best_length_ratio 0.4)
				(max_length 1)
				(best_width_ratio 0.9)
				(max_width 2)
				(curved_edges yes)
				(filter_ratio 0.9)
				(enabled yes)
				(allow_two_segments yes)
				(prefer_zone_connections yes)
			)
		)
	)
)
